(kicad_pcb
	(version 20241229)
	(generator "pcbnew")
	(generator_version "9.0")
	(general
		(thickness 1.294)
		(legacy_teardrops no)
	)
	(paper "A3")
	(title_block
		(title "Kintex 410T devboard")
		(date "2024-04-03")
		(rev "1.1.2")
		(comment 9 "footprints 125-129 of 975")
	)
	(layers
		(0 "F.Cu" mixed)
		(4 "In1.Cu" power)
		(6 "In2.Cu" power)
		(8 "In3.Cu" mixed)
		(10 "In4.Cu" power)
		(12 "In5.Cu" mixed)
		(14 "In6.Cu" power)
		(16 "In7.Cu" mixed)
		(18 "In8.Cu" power)
		(2 "B.Cu" mixed)
		(9 "F.Adhes" user "F.Adhesive")
		(11 "B.Adhes" user "B.Adhesive")
		(13 "F.Paste" user)
		(15 "B.Paste" user)
		(5 "F.SilkS" user "F.Silkscreen")
		(7 "B.SilkS" user "B.Silkscreen")
		(1 "F.Mask" user)
		(3 "B.Mask" user)
		(17 "Dwgs.User" user "User.Drawings")
		(19 "Cmts.User" user "User.Comments")
		(21 "Eco1.User" user "User.Eco1")
		(23 "Eco2.User" user "User.Eco2")
		(25 "Edge.Cuts" user)
		(27 "Margin" user)
		(31 "F.CrtYd" user "F.Courtyard")
		(29 "B.CrtYd" user "B.Courtyard")
		(35 "F.Fab" user)
		(33 "B.Fab" user)
	)
	(footprint "antmicro-footprints:C_0402_1005Metric"
		(layer "F.Cu")
		(at 194.501 101.949 90)
		(descr "Capacitor SMD 0402")
		(tags "capacitor SMD 0402")
		(property "Reference" "C223"
			(at -1.351 -0.501 90)
			(layer "F.SilkS")
			(effects
				(font
					(size 0.7 0.7)
					(thickness 0.15)
				)
				(justify left bottom)
			)
		)
		(property "Value" "C_22p_0402"
			(at 0 1.4 90)
			(layer "F.Fab")
			(effects
				(font
					(size 0.7 0.7)
					(thickness 0.15)
				)
				(justify left bottom)
			)
		)
		(property "Description" "SMD Multilayer Ceramic Capacitor, 22 pF, 50 V, 0402 [1005 Metric], ± 5%, C0G / NP0, CC Series"
			(at 0 0 90)
			(layer "F.Fab")
			(hide yes)
			(effects
				(font
					(size 1.27 1.27)
					(thickness 0.15)
				)
			)
		)
		(property "Author" "Antmicro"
			(at 296.45 -92.552 0)
			(layer "F.Fab")
			(hide yes)
			(effects
				(font
					(size 1 1)
					(thickness 0.15)
				)
			)
		)
		(property "Dielectric" ""
			(at 296.45 -92.552 0)
			(layer "F.Fab")
			(hide yes)
			(effects
				(font
					(size 1 1)
					(thickness 0.15)
				)
			)
		)
		(property "License" "Apache-2.0"
			(at 296.45 -92.552 0)
			(layer "F.Fab")
			(hide yes)
			(effects
				(font
					(size 1 1)
					(thickness 0.15)
				)
			)
		)
		(property "MPN" "CC0402JRNPO9BN220"
			(at 296.45 -92.552 0)
			(layer "F.Fab")
			(hide yes)
			(effects
				(font
					(size 1 1)
					(thickness 0.15)
				)
			)
		)
		(property "Manufacturer" "YAGEO"
			(at 296.45 -92.552 0)
			(layer "F.Fab")
			(hide yes)
			(effects
				(font
					(size 1 1)
					(thickness 0.15)
				)
			)
		)
		(property "Val" "22p"
			(at 296.45 -92.552 0)
			(layer "F.Fab")
			(hide yes)
			(effects
				(font
					(size 1 1)
					(thickness 0.15)
				)
			)
		)
		(property "Voltage" ""
			(at 296.45 -92.552 0)
			(layer "F.Fab")
			(hide yes)
			(effects
				(font
					(size 1 1)
					(thickness 0.15)
				)
			)
		)
		(sheetname "USB PHY")
		(sheetfile "usb-phy.kicad_sch")
		(attr smd)
		(fp_rect
			(start -0.925 -0.47)
			(end 0.925 0.47)
			(stroke
				(width 0.05)
				(type default)
			)
			(fill no)
			(layer "F.CrtYd")
		)
		(fp_line
			(start 0.504 -0.25)
			(end 0.504 0.248)
			(stroke
				(width 0.15)
				(type solid)
			)
			(layer "F.Fab")
		)
		(fp_line
			(start -0.494 -0.25)
			(end 0.504 -0.25)
			(stroke
				(width 0.15)
				(type solid)
			)
			(layer "F.Fab")
		)
		(fp_line
			(start 0.504 0.248)
			(end -0.494 0.248)
			(stroke
				(width 0.15)
				(type solid)
			)
			(layer "F.Fab")
		)
		(fp_line
			(start -0.494 0.248)
			(end -0.494 -0.25)
			(stroke
				(width 0.15)
				(type solid)
			)
			(layer "F.Fab")
		)
		(pad "1" smd roundrect
			(at -0.48 0 90)
			(size 0.59 0.64)
			(layers "F.Cu" "F.Mask" "F.Paste")
			(roundrect_rratio 0.25)
			(net 1 "GND")
			(pintype "passive")
		)
		(pad "2" smd roundrect
			(at 0.48 0 90)
			(size 0.59 0.64)
			(layers "F.Cu" "F.Mask" "F.Paste")
			(roundrect_rratio 0.25)
			(net 708 "/USB PHY/USB_HOST_XO")
			(pintype "passive")
		)
	)
	(footprint "antmicro-footprints:SOT-886"
		(layer "F.Cu")
		(at 155.6 149.9)
		(property "Reference" "U47"
			(at -0.45 1.55 0)
			(layer "F.SilkS")
			(effects
				(font
					(size 0.7 0.7)
					(thickness 0.15)
				)
				(justify left bottom)
			)
		)
		(property "Value" "74LVC1T45GM"
			(at -2.492 1.647 0)
			(layer "F.Fab")
			(effects
				(font
					(size 0.7 0.7)
					(thickness 0.15)
				)
				(justify left bottom)
			)
		)
		(property "Description" "Transceiver, Translating, 74LVC1T45, 74LVC Family, 1.2V to 5.5V Supply, XSON-6"
			(at 0 0 0)
			(layer "F.Fab")
			(hide yes)
			(effects
				(font
					(size 1.27 1.27)
					(thickness 0.15)
				)
			)
		)
		(property "Author" "Antmicro"
			(at 0 0 0)
			(layer "F.Fab")
			(hide yes)
			(effects
				(font
					(size 1 1)
					(thickness 0.15)
				)
			)
		)
		(property "License" "Apache-2.0"
			(at 0 0 0)
			(layer "F.Fab")
			(hide yes)
			(effects
				(font
					(size 1 1)
					(thickness 0.15)
				)
			)
		)
		(property "MPN" "74LVC1T45GM-Q100X"
			(at 0 0 0)
			(layer "F.Fab")
			(hide yes)
			(effects
				(font
					(size 1 1)
					(thickness 0.15)
				)
			)
		)
		(property "Manufacturer" "Nexperia"
			(at 0 0 0)
			(layer "F.Fab")
			(hide yes)
			(effects
				(font
					(size 1 1)
					(thickness 0.15)
				)
			)
		)
		(sheetname "DC-DC Converters")
		(sheetfile "dc-dc.kicad_sch")
		(attr smd)
		(fp_line
			(start -0.843 -0.491)
			(end -0.843 0.183)
			(stroke
				(width 0.15)
				(type solid)
			)
			(layer "F.SilkS")
		)
		(fp_line
			(start 0.858 -0.491)
			(end 0.858 0.509)
			(stroke
				(width 0.15)
				(type solid)
			)
			(layer "F.SilkS")
		)
		(fp_circle
			(center -0.493 0.847)
			(end -0.443 0.847)
			(stroke
				(width 0.15)
				(type solid)
			)
			(fill yes)
			(layer "F.SilkS")
		)
		(fp_rect
			(start -1.23 -1)
			(end 1.22 0.99)
			(stroke
				(width 0.05)
				(type solid)
			)
			(fill no)
			(layer "F.CrtYd")
		)
		(fp_line
			(start -0.843 -0.616)
			(end -0.843 0.634)
			(stroke
				(width 0.15)
				(type solid)
			)
			(layer "F.Fab")
		)
		(fp_line
			(start -0.843 -0.616)
			(end 0.858 -0.616)
			(stroke
				(width 0.15)
				(type solid)
			)
			(layer "F.Fab")
		)
		(fp_line
			(start -0.843 0.434)
			(end -0.644 0.634)
			(stroke
				(width 0.15)
				(type solid)
			)
			(layer "F.Fab")
		)
		(fp_line
			(start 0.858 -0.616)
			(end 0.858 0.634)
			(stroke
				(width 0.15)
				(type solid)
			)
			(layer "F.Fab")
		)
		(fp_line
			(start 0.858 0.634)
			(end -0.843 0.634)
			(stroke
				(width 0.15)
				(type solid)
			)
			(layer "F.Fab")
		)
		(pad "1" smd rect
			(at -0.493 0.347)
			(size 0.27 0.325)
			(layers "F.Cu" "F.Mask" "F.Paste")
			(net 24 "+3V3")
			(pinfunction "VCCA")
			(pintype "power_in")
			(solder_mask_margin 0.05)
		)
		(pad "2" smd rect
			(at 0.005 0.347)
			(size 0.27 0.325)
			(layers "F.Cu" "F.Mask" "F.Paste")
			(net 1 "GND")
			(pinfunction "GND")
			(pintype "power_in")
			(solder_mask_margin 0.05)
		)
		(pad "3" smd rect
			(at 0.505 0.347)
			(size 0.27 0.325)
			(layers "F.Cu" "F.Mask" "F.Paste")
			(net 1191 "/DC-DC Converters/+0V675_EN")
			(pinfunction "A")
			(pintype "bidirectional")
			(solder_mask_margin 0.05)
		)
		(pad "4" smd rect
			(at 0.505 -0.33 180)
			(size 0.27 0.325)
			(layers "F.Cu" "F.Mask" "F.Paste")
			(net 25 "+1V35")
			(pinfunction "B")
			(pintype "bidirectional")
			(solder_mask_margin 0.05)
		)
		(pad "5" smd rect
			(at 0.005 -0.33 180)
			(size 0.27 0.325)
			(layers "F.Cu" "F.Mask" "F.Paste")
			(net 1 "GND")
			(pinfunction "DIR")
			(pintype "input")
			(solder_mask_margin 0.05)
		)
		(pad "6" smd rect
			(at -0.493 -0.33 180)
			(size 0.27 0.325)
			(layers "F.Cu" "F.Mask" "F.Paste")
			(net 25 "+1V35")
			(pinfunction "VCCB")
			(pintype "power_in")
			(solder_mask_margin 0.05)
		)
	)
	(footprint "antmicro-footprints:LED_0603_1608Metric_G"
		(layer "F.Cu")
		(at 261.5 86.2)
		(descr "LED SMD 0603 Green")
		(tags "LED SMD 0603 Green")
		(property "Reference" "D19"
			(at -1.05 1.5 0)
			(layer "F.SilkS")
			(effects
				(font
					(size 0.7 0.7)
					(thickness 0.15)
				)
				(justify left bottom)
			)
		)
		(property "Value" "LED_G_0603_KP-1608CGCK"
			(at 0 1.6 0)
			(layer "F.Fab")
			(effects
				(font
					(size 0.7 0.7)
					(thickness 0.15)
				)
				(justify left bottom)
			)
		)
		(property "Description" "LED, Green, SMD, 0603, 20 mA, 2.1 V, 570 nm"
			(at 0 0 0)
			(layer "F.Fab")
			(hide yes)
			(effects
				(font
					(size 1.27 1.27)
					(thickness 0.15)
				)
			)
		)
		(property "Author" "Antmicro"
			(at 0 0 0)
			(layer "F.Fab")
			(hide yes)
			(effects
				(font
					(size 1 1)
					(thickness 0.15)
				)
			)
		)
		(property "Color" "Green"
			(at 0 0 0)
			(layer "F.Fab")
			(hide yes)
			(effects
				(font
					(size 1 1)
					(thickness 0.15)
				)
			)
		)
		(property "License" "Apache-2.0"
			(at 0 0 0)
			(layer "F.Fab")
			(hide yes)
			(effects
				(font
					(size 1 1)
					(thickness 0.15)
				)
			)
		)
		(property "MPN" "KP-1608CGCK"
			(at 0 0 0)
			(layer "F.Fab")
			(hide yes)
			(effects
				(font
					(size 1 1)
					(thickness 0.15)
				)
			)
		)
		(property "Manufacturer" "Kingbright"
			(at 0 0 0)
			(layer "F.Fab")
			(hide yes)
			(effects
				(font
					(size 1 1)
					(thickness 0.15)
				)
			)
		)
		(sheetname "User GPIO + LED + button + DIP switch")
		(sheetfile "user-gpio.kicad_sch")
		(attr smd)
		(fp_line
			(start -1.18 -0.319)
			(end -1.18 0.321)
			(stroke
				(width 0.15)
				(type solid)
			)
			(layer "F.SilkS")
		)
		(fp_line
			(start -0.094672 0.001008)
			(end -0.24 0.001008)
			(stroke
				(width 0.1)
				(type solid)
			)
			(layer "F.SilkS")
		)
		(fp_line
			(start -0.094672 0.001008)
			(end 0.105328 -0.198992)
			(stroke
				(width 0.1)
				(type solid)
			)
			(layer "F.SilkS")
		)
		(fp_line
			(start -0.094672 0.201008)
			(end -0.094672 -0.198992)
			(stroke
				(width 0.1)
				(type solid)
			)
			(layer "F.SilkS")
		)
		(fp_line
			(start 0.105328 0.001008)
			(end 0.24 0.001)
			(stroke
				(width 0.1)
				(type solid)
			)
			(layer "F.SilkS")
		)
		(fp_line
			(start 0.105328 0.201008)
			(end -0.094672 0.001008)
			(stroke
				(width 0.1)
				(type solid)
			)
			(layer "F.SilkS")
		)
		(fp_line
			(start 0.105328 0.201008)
			(end 0.105328 -0.198992)
			(stroke
				(width 0.1)
				(type solid)
			)
			(layer "F.SilkS")
		)
		(fp_line
			(start 0.22 -0.35)
			(end -0.22 -0.35)
			(stroke
				(width 0.15)
				(type solid)
			)
			(layer "F.SilkS")
		)
		(fp_line
			(start 0.22 0.35)
			(end -0.22 0.35)
			(stroke
				(width 0.15)
				(type solid)
			)
			(layer "F.SilkS")
		)
		(fp_rect
			(start 1.25 0.65)
			(end -1.25 -0.65)
			(stroke
				(width 0.05)
				(type solid)
			)
			(fill no)
			(layer "F.CrtYd")
		)
		(fp_line
			(start -0.199 -0.202)
			(end -0.199 0.1)
			(stroke
				(width 0.15)
				(type solid)
			)
			(layer "F.Fab")
		)
		(fp_line
			(start -0.199 0)
			(end -0.597 0)
			(stroke
				(width 0.15)
				(type solid)
			)
			(layer "F.Fab")
		)
		(fp_line
			(start -0.199 0.2)
			(end -0.199 0.1)
			(stroke
				(width 0.15)
				(type solid)
			)
			(layer "F.Fab")
		)
		(fp_line
			(start -0.101 0)
			(end 0.201 0.2)
			(stroke
				(width 0.15)
				(type solid)
			)
			(layer "F.Fab")
		)
		(fp_line
			(start 0.201 -0.202)
			(end -0.101 0)
			(stroke
				(width 0.15)
				(type solid)
			)
			(layer "F.Fab")
		)
		(fp_line
			(start 0.201 0)
			(end 0.201 -0.202)
			(stroke
				(width 0.15)
				(type solid)
			)
			(layer "F.Fab")
		)
		(fp_line
			(start 0.201 0.2)
			(end 0.201 0)
			(stroke
				(width 0.15)
				(type solid)
			)
			(layer "F.Fab")
		)
		(fp_line
			(start 0.599 0)
			(end 0.201 0)
			(stroke
				(width 0.15)
				(type solid)
			)
			(layer "F.Fab")
		)
		(fp_rect
			(start 0.848 0.4)
			(end -0.85 -0.402)
			(stroke
				(width 0.15)
				(type solid)
			)
			(fill no)
			(layer "F.Fab")
		)
		(pad "1" smd roundrect
			(at -0.7 0 180)
			(size 0.8 1)
			(layers "F.Cu" "F.Mask" "F.Paste")
			(roundrect_rratio 0.2)
			(net 21 "Net-(D19-C)")
			(pinfunction "C")
			(pintype "passive")
		)
		(pad "2" smd roundrect
			(at 0.7 0 180)
			(size 0.8 1)
			(layers "F.Cu" "F.Mask" "F.Paste")
			(roundrect_rratio 0.2)
			(net 777 "Net-(D19-A)")
			(pinfunction "A")
			(pintype "passive")
		)
	)
	(footprint "antmicro-footprints:R_0402_1005Metric"
		(layer "F.Cu")
		(at 219.2 142.4 180)
		(descr "Resistor SMD 0402")
		(tags "resistor SMD 0402")
		(property "Reference" "R337"
			(at 3.65 -0.4 180)
			(layer "F.SilkS")
			(effects
				(font
					(size 0.7 0.7)
					(thickness 0.15)
				)
				(justify left bottom)
			)
		)
		(property "Value" "R_22R_0402"
			(at 0 1.4 180)
			(layer "F.Fab")
			(effects
				(font
					(size 0.7 0.7)
					(thickness 0.15)
				)
				(justify left bottom)
			)
		)
		(property "Description" "SMD Chip Resistor, 22 ohm, ± 1%, 62.5 mW, 0402 [1005 Metric], Thick Film, General Purpose"
			(at 0 0 180)
			(layer "F.Fab")
			(hide yes)
			(effects
				(font
					(size 1.27 1.27)
					(thickness 0.15)
				)
			)
		)
		(property "Author" "Antmicro"
			(at 438.4 284.8 0)
			(layer "F.Fab")
			(hide yes)
			(effects
				(font
					(size 1 1)
					(thickness 0.15)
				)
			)
		)
		(property "License" "Apache-2.0"
			(at 438.4 284.8 0)
			(layer "F.Fab")
			(hide yes)
			(effects
				(font
					(size 1 1)
					(thickness 0.15)
				)
			)
		)
		(property "MPN" "CR0402-FX-22R0GLF"
			(at 438.4 284.8 0)
			(layer "F.Fab")
			(hide yes)
			(effects
				(font
					(size 1 1)
					(thickness 0.15)
				)
			)
		)
		(property "Manufacturer" "Bourns"
			(at 438.4 284.8 0)
			(layer "F.Fab")
			(hide yes)
			(effects
				(font
					(size 1 1)
					(thickness 0.15)
				)
			)
		)
		(property "Tolerance" "1%"
			(at 438.4 284.8 0)
			(layer "F.Fab")
			(hide yes)
			(effects
				(font
					(size 1 1)
					(thickness 0.15)
				)
			)
		)
		(property "Val" "22R"
			(at 438.4 284.8 0)
			(layer "F.Fab")
			(hide yes)
			(effects
				(font
					(size 1 1)
					(thickness 0.15)
				)
			)
		)
		(sheetname "Clocks")
		(sheetfile "clocks.kicad_sch")
		(attr smd)
		(fp_rect
			(start -0.925 -0.47)
			(end 0.925 0.47)
			(stroke
				(width 0.05)
				(type default)
			)
			(fill no)
			(layer "F.CrtYd")
		)
		(fp_rect
			(start -0.5 -0.25)
			(end 0.5 0.25)
			(stroke
				(width 0.15)
				(type solid)
			)
			(fill no)
			(layer "F.Fab")
		)
		(pad "1" smd roundrect
			(at -0.48 0 180)
			(size 0.59 0.64)
			(layers "F.Cu" "F.Mask" "F.Paste")
			(roundrect_rratio 0.25)
			(net 973 "/Clocks/PLL_Y4")
			(pintype "passive")
		)
		(pad "2" smd roundrect
			(at 0.48 0 180)
			(size 0.59 0.64)
			(layers "F.Cu" "F.Mask" "F.Paste")
			(roundrect_rratio 0.25)
			(net 1403 "/PLL.CLK1")
			(pintype "passive")
		)
	)
	(footprint "antmicro-footprints:C_0603_1608Metric"
		(layer "F.Cu")
		(at 157.95 165.55 180)
		(descr "Capacitor SMD 0603")
		(tags "capacitor 0603")
		(property "Reference" "C322"
			(at 1.05 -0.4 0)
			(layer "F.SilkS")
			(effects
				(font
					(size 0.7 0.7)
					(thickness 0.15)
				)
				(justify right bottom)
			)
		)
		(property "Value" "C_22u_0603"
			(at 0 1.6 0)
			(layer "F.Fab")
			(effects
				(font
					(size 0.7 0.7)
					(thickness 0.15)
				)
				(justify right bottom)
			)
		)
		(property "Description" "SMD Multilayer Ceramic Capacitor, 22 µF, 6.3 V, 0603 [1608 Metric], ± 20%, X5R, GRM Series"
			(at 0 0 180)
			(layer "F.Fab")
			(hide yes)
			(effects
				(font
					(size 1.27 1.27)
					(thickness 0.15)
				)
			)
		)
		(property "Author" "Antmicro"
			(at 315.9 331.1 0)
			(layer "F.Fab")
			(hide yes)
			(effects
				(font
					(size 1 1)
					(thickness 0.15)
				)
			)
		)
		(property "Dielectric" ""
			(at 315.9 331.1 0)
			(layer "F.Fab")
			(hide yes)
			(effects
				(font
					(size 1 1)
					(thickness 0.15)
				)
			)
		)
		(property "License" "Apache-2.0"
			(at 315.9 331.1 0)
			(layer "F.Fab")
			(hide yes)
			(effects
				(font
					(size 1 1)
					(thickness 0.15)
				)
			)
		)
		(property "MPN" "GRM188R60J226MEA0D"
			(at 315.9 331.1 0)
			(layer "F.Fab")
			(hide yes)
			(effects
				(font
					(size 1 1)
					(thickness 0.15)
				)
			)
		)
		(property "Manufacturer" "Murata"
			(at 315.9 331.1 0)
			(layer "F.Fab")
			(hide yes)
			(effects
				(font
					(size 1 1)
					(thickness 0.15)
				)
			)
		)
		(property "Val" "22u"
			(at 315.9 331.1 0)
			(layer "F.Fab")
			(hide yes)
			(effects
				(font
					(size 1 1)
					(thickness 0.15)
				)
			)
		)
		(property "Voltage" ""
			(at 315.9 331.1 0)
			(layer "F.Fab")
			(hide yes)
			(effects
				(font
					(size 1 1)
					(thickness 0.15)
				)
			)
		)
		(sheetname "DC-DC Converters")
		(sheetfile "dc-dc.kicad_sch")
		(attr smd)
		(fp_line
			(start -0.15 0.4)
			(end 0.15 0.4)
			(stroke
				(width 0.15)
				(type solid)
			)
			(layer "F.SilkS")
		)
		(fp_line
			(start -0.15 -0.4)
			(end 0.15 -0.4)
			(stroke
				(width 0.15)
				(type solid)
			)
			(layer "F.SilkS")
		)
		(fp_rect
			(start -1.25 -0.65)
			(end 1.25 0.65)
			(stroke
				(width 0.05)
				(type solid)
			)
			(fill no)
			(layer "F.CrtYd")
		)
		(fp_rect
			(start -0.8 -0.4)
			(end 0.8 0.4)
			(stroke
				(width 0.15)
				(type solid)
			)
			(fill no)
			(layer "F.Fab")
		)
		(pad "1" smd roundrect
			(at -0.7 0 180)
			(size 0.8 1)
			(layers "F.Cu" "F.Mask" "F.Paste")
			(roundrect_rratio 0.2)
			(net 1 "GND")
			(pintype "passive")
		)
		(pad "2" smd roundrect
			(at 0.7 0 180)
			(size 0.8 1)
			(layers "F.Cu" "F.Mask" "F.Paste")
			(roundrect_rratio 0.2)
			(net 733 "/DC-DC Converters/MGTAVCC_local")
			(pintype "passive")
		)
	)
)
